#ISCELL
  mstr_misc dns *
  *
#ISCELL
  pure_quanta quanta_title_block_c *
  *
#ISCELL
  pure_quanta_power design_note *
  *
#CELL
  pure_quanta 9zxl0451ekilft *
  page112_i1
#CELL
  pure_quanta q_res *
  page112_i100
#CELL
  pure_quanta q_res *
  page112_i101
#CELL
  pure_quanta q_res *
  page112_i102
#CELL
  pure_quanta q_res *
  page112_i103
#CELL
  pure_quanta q_res *
  page112_i104
#CELL
  pure_quanta q_res *
  page112_i105
#CELL
  pure_quanta q_res *
  page112_i106
#CELL
  pure_quanta q_res *
  page112_i107
#CELL
  pure_quanta q_res *
  page112_i110
#ISCELL
  standard offpage *
  page112_i111
#ISCELL
  standard offpage *
  page112_i112
#ISCELL
  standard offpage *
  page112_i113
#ISCELL
  standard offpage *
  page112_i114
#ISCELL
  standard offpage *
  page112_i115
#ISCELL
  standard offpage *
  page112_i116
#ISCELL
  standard offpage *
  page112_i117
#ISCELL
  standard offpage *
  page112_i118
#ISCELL
  standard offpage *
  page112_i119
#ISCELL
  standard offpage *
  page112_i120
#ISCELL
  pure_quanta_power universal_gnd *
  page112_i121
#CELL
  pure_quanta q_cap *
  page112_i122
#CELL
  pure_quanta q_cap *
  page112_i126
#ISCELL
  pure_quanta_power universal_gnd *
  page112_i127
#CELL
  pure_quanta q_cap *
  page112_i128
#ISCELL
  pure_quanta_power universal_gnd *
  page112_i129
#ISCELL
  pure_quanta_power universal_gnd *
  page112_i130
#CELL
  pure_quanta q_cap *
  page112_i131
#ISCELL
  pure_quanta_power universal_gnd *
  page112_i137
#CELL
  pure_quanta q_cap *
  page112_i138
#ISCELL
  pure_quanta_power universal_gnd *
  page112_i139
#CELL
  pure_quanta q_cap *
  page112_i140
#ISCELL
  pure_quanta_power universal_power *
  page112_i141
#CELL
  pure_quanta q_inductor *
  page112_i142
#ISCELL
  pure_quanta_power universal_power *
  page112_i143
#ISCELL
  pure_quanta_power universal_power *
  page112_i144
#ISCELL
  pure_quanta_power universal_gnd *
  page112_i145
#CELL
  pure_quanta q_cap *
  page112_i146
#ISCELL
  pure_quanta_power universal_gnd *
  page112_i147
#CELL
  pure_quanta q_cap *
  page112_i149
#CELL
  pure_quanta q_inductor *
  page112_i151
#ISCELL
  pure_quanta_power universal_gnd *
  page112_i154
#ISCELL
  pure_quanta_power universal_gnd *
  page112_i155
#CELL
  pure_quanta q_cap *
  page112_i156
#CELL
  pure_quanta q_cap *
  page112_i158
#ISCELL
  pure_quanta_power universal_gnd *
  page112_i160
#ISCELL
  pure_quanta_power universal_gnd *
  page112_i161
#CELL
  pure_quanta q_cap *
  page112_i162
#CELL
  pure_quanta q_cap *
  page112_i163
#ISCELL
  pure_quanta_power universal_power *
  page112_i166
#CELL
  pure_quanta q_res *
  page112_i167
#ISCELL
  pure_quanta_power universal_gnd *
  page112_i172
#CELL
  pure_quanta q_cap *
  page112_i173
#ISCELL
  pure_quanta_power universal_gnd *
  page112_i174
#CELL
  pure_quanta q_cap *
  page112_i175
#ISCELL
  pure_quanta_power universal_gnd *
  page112_i176
#CELL
  pure_quanta q_cap *
  page112_i177
#CELL
  pure_quanta q_res *
  page112_i178
#ISCELL
  pure_quanta_power vcc_core *
  page112_i179
#ISCELL
  pure_quanta_power universal_gnd *
  page112_i180
#ISCELL
  pure_quanta_power universal_gnd *
  page112_i181
#CELL
  pure_quanta q_cap *
  page112_i182
#CELL
  pure_quanta q_cap *
  page112_i183
#ISCELL
  pure_quanta_power universal_gnd *
  page112_i184
#CELL
  pure_quanta q_cap *
  page112_i185
#ISCELL
  pure_quanta_power vcc_core *
  page112_i186
#ISCELL
  pure_quanta_power universal_gnd *
  page112_i187
#ISCELL
  pure_quanta_power universal_power *
  page112_i188
#CELL
  pure_quanta q_res *
  page112_i189
#CELL
  pure_quanta q_res *
  page112_i190
#ISCELL
  pure_quanta_power universal_gnd *
  page112_i191
#ISCELL
  pure_quanta_power universal_power *
  page112_i192
#CELL
  pure_quanta q_res *
  page112_i193
#CELL
  pure_quanta q_res *
  page112_i194
#ISCELL
  pure_quanta_power universal_gnd *
  page112_i195
#ISCELL
  pure_quanta_power universal_gnd *
  page112_i196
#CELL
  pure_quanta q_res *
  page112_i197
#ISCELL
  pure_quanta_power universal_power *
  page112_i199
#CELL
  pure_quanta 9zxl0451ekilft *
  page112_i2
#ISCELL
  pure_quanta_power universal_gnd *
  page112_i200
#ISCELL
  pure_quanta_power universal_power *
  page112_i201
#ISCELL
  pure_quanta_power universal_gnd *
  page112_i204
#ISCELL
  standard offpage *
  page112_i205
#ISCELL
  standard offpage *
  page112_i206
#ISCELL
  standard offpage *
  page112_i207
#ISCELL
  standard offpage *
  page112_i208
#ISCELL
  standard offpage *
  page112_i209
#ISCELL
  standard offpage *
  page112_i210
#CELL
  pure_quanta q_res *
  page112_i211
#CELL
  pure_quanta q_res *
  page112_i212
#ISCELL
  standard offpage *
  page112_i213
#ISCELL
  standard offpage *
  page112_i214
#CELL
  pure_quanta q_res *
  page112_i215
#CELL
  pure_quanta q_res *
  page112_i216
#CELL
  pure_quanta q_res *
  page112_i217
#CELL
  pure_quanta q_res *
  page112_i219
#CELL
  pure_quanta q_res *
  page112_i220
#ISCELL
  standard offpage *
  page112_i221
#ISCELL
  standard offpage *
  page112_i222
#ISCELL
  standard offpage *
  page112_i234
#ISCELL
  standard offpage *
  page112_i235
#ISCELL
  standard offpage *
  page112_i237
#CELL
  pure_quanta q_res *
  page112_i240
#ISCELL
  pure_quanta_power universal_gnd *
  page112_i241
#CELL
  pure_quanta q_res *
  page112_i242
#CELL
  pure_quanta q_res *
  page112_i243
#ISCELL
  standard offpage *
  page112_i244
#ISCELL
  standard offpage *
  page112_i246
#CELL
  pure_quanta q_res *
  page112_i250
#CELL
  pure_quanta q_res *
  page112_i251
#ISCELL
  pure_quanta_power universal_gnd *
  page112_i253
#ISCELL
  pure_quanta_power universal_gnd *
  page112_i254
#CELL
  pure_quanta q_res *
  page112_i255
#CELL
  pure_quanta q_res *
  page112_i256
#ISCELL
  pure_quanta_power universal_power *
  page112_i257
#CELL
  pure_quanta q_res *
  page112_i258
#CELL
  pure_quanta q_res *
  page112_i259
#ISCELL
  standard offpage *
  page112_i260
#ISCELL
  standard offpage *
  page112_i261
#CELL
  pure_quanta q_res *
  page112_i262
#ISCELL
  standard offpage *
  page112_i263
#CELL
  pure_quanta q_res *
  page112_i264
#ISCELL
  standard offpage *
  page112_i265
#ISCELL
  standard offpage *
  page112_i266
#ISCELL
  standard offpage *
  page112_i267
#CELL
  pure_quanta q_res *
  page112_i268
#CELL
  pure_quanta q_res *
  page112_i269
#CELL
  pure_quanta q_res *
  page112_i270
#ISCELL
  standard offpage *
  page112_i272
#ISCELL
  pure_quanta_power vcc_core *
  page112_i3
#ISCELL
  pure_quanta_power universal_power *
  page112_i4
#ISCELL
  pure_quanta_power vcc_core *
  page112_i5
#ISCELL
  pure_quanta_power vcc_core *
  page112_i6
#ISCELL
  pure_quanta_power universal_power *
  page112_i7
#ISCELL
  standard offpage *
  page112_i77
#ISCELL
  standard offpage *
  page112_i78
#ISCELL
  pure_quanta_power vcc_core *
  page112_i8
#CELL
  pure_quanta q_res *
  page112_i99
